(kicad_pcb
	(version 20260206)
	(generator "pcbnew")
	(generator_version "10.0")
	(general
		(thickness 1.6)
		(legacy_teardrops no)
	)
	(paper "A4")
	(title_block
		(title "04192023_DAF0TMB3IC0_F0TG_MB_C_brd_V02_OCP.brd")
		(comment 1 "Grand Teton / footprints 7061-7067 of 8354")
	)
	(layers
		(0 "F.Cu" signal "TOP")
		(4 "In1.Cu" signal "GND")
		(6 "In2.Cu" signal "IN1")
		(8 "In3.Cu" signal "GND1")
		(10 "In4.Cu" signal "IN2")
		(12 "In5.Cu" signal "GND2")
		(14 "In6.Cu" signal "IN3")
		(16 "In7.Cu" signal "GND3")
		(18 "In8.Cu" signal "VCC")
		(20 "In9.Cu" signal "VCC1")
		(22 "In10.Cu" signal "GND4")
		(24 "In11.Cu" signal "IN4")
		(26 "In12.Cu" signal "GND5")
		(28 "In13.Cu" signal "IN5")
		(30 "In14.Cu" signal "GND6")
		(32 "In15.Cu" signal "IN6")
		(34 "In16.Cu" signal "GND7")
		(2 "B.Cu" signal "BOTTOM")
		(9 "F.Adhes" user "F.Adhesive")
		(11 "B.Adhes" user "B.Adhesive")
		(13 "F.Paste" user "Package Geometry/Pastemask Top")
		(15 "B.Paste" user "Package Geometry/Pastemask Bottom")
		(5 "F.SilkS" user "Ref Des/Silkscreen Top")
		(7 "B.SilkS" user "Ref Des/Silkscreen Bottom")
		(1 "F.Mask" user "Board Geometry/Soldermask Top")
		(3 "B.Mask" user "Board Geometry/Soldermask Bottom")
		(17 "Dwgs.User" user "User.Drawings")
		(19 "Cmts.User" user "User.Comments")
		(21 "Eco1.User" user "User.Eco1")
		(23 "Eco2.User" user "User.Eco2")
		(25 "Edge.Cuts" user "Board Geometry/Outline")
		(27 "Margin" user)
		(31 "F.CrtYd" user "Package Geometry/Place Bound Top")
		(29 "B.CrtYd" user "Package Geometry/Place Bound Bottom")
		(35 "F.Fab" user "Ref Des/Assembly Top")
		(33 "B.Fab" user "Ref Des/Assembly Bottom")
	)
	(footprint ""
		(layer "B.Cu")
		(at 350.818958 -250.89231 180)
		(property "Reference" "C276"
			(at 0 0 0)
			(layer "B.SilkS")
			(hide yes)
			(effects
				(font
					(size 1.27 1.27)
				)
				(justify mirror)
			)
		)
		(property "Value" ""
			(at 0 0 0)
			(layer "B.Fab")
			(effects
				(font
					(size 1.27 1.27)
				)
				(justify mirror)
			)
		)
		(duplicate_pad_numbers_are_jumpers no)
		(fp_line
			(start 0.7874 0.4064)
			(end 0.7874 -0.4064)
			(stroke
				(width 0.1524)
				(type default)
			)
			(layer "B.SilkS")
		)
		(fp_line
			(start 0.7874 -0.4064)
			(end -0.7874 -0.4064)
			(stroke
				(width 0.1524)
				(type default)
			)
			(layer "B.SilkS")
		)
		(fp_line
			(start -0.7874 0.4064)
			(end 0.7874 0.4064)
			(stroke
				(width 0.1524)
				(type default)
			)
			(layer "B.SilkS")
		)
		(fp_line
			(start -0.7874 -0.4064)
			(end -0.7874 0.4064)
			(stroke
				(width 0.1524)
				(type default)
			)
			(layer "B.SilkS")
		)
		(fp_line
			(start 0.67945 0.3048)
			(end 0.67945 -0.305054)
			(stroke
				(width 0.1)
				(type default)
			)
			(layer "B.Fab")
		)
		(fp_line
			(start 0.67945 -0.305054)
			(end 0.12065 -0.305054)
			(stroke
				(width 0.1)
				(type default)
			)
			(layer "B.Fab")
		)
		(fp_line
			(start 0.12065 0.3048)
			(end 0.67945 0.3048)
			(stroke
				(width 0.1)
				(type default)
			)
			(layer "B.Fab")
		)
		(fp_line
			(start 0.12065 0.2794)
			(end 0.12065 0.3048)
			(stroke
				(width 0.1)
				(type default)
			)
			(layer "B.Fab")
		)
		(fp_line
			(start 0.12065 -0.2794)
			(end -0.12065 -0.2794)
			(stroke
				(width 0.1)
				(type default)
			)
			(layer "B.Fab")
		)
		(fp_line
			(start 0.12065 -0.305054)
			(end 0.12065 -0.2794)
			(stroke
				(width 0.1)
				(type default)
			)
			(layer "B.Fab")
		)
		(fp_line
			(start -0.120396 0.3048)
			(end -0.120396 0.2794)
			(stroke
				(width 0.1)
				(type default)
			)
			(layer "B.Fab")
		)
		(fp_line
			(start -0.120396 0.2794)
			(end 0.12065 0.2794)
			(stroke
				(width 0.1)
				(type default)
			)
			(layer "B.Fab")
		)
		(fp_line
			(start -0.12065 -0.2794)
			(end -0.12065 -0.3048)
			(stroke
				(width 0.1)
				(type default)
			)
			(layer "B.Fab")
		)
		(fp_line
			(start -0.12065 -0.3048)
			(end -0.67945 -0.3048)
			(stroke
				(width 0.1)
				(type default)
			)
			(layer "B.Fab")
		)
		(fp_line
			(start -0.67945 0.3048)
			(end -0.120396 0.3048)
			(stroke
				(width 0.1)
				(type default)
			)
			(layer "B.Fab")
		)
		(fp_line
			(start -0.67945 -0.3048)
			(end -0.67945 0.3048)
			(stroke
				(width 0.1)
				(type default)
			)
			(layer "B.Fab")
		)
		(pad "1" smd circle
			(at 0.40005 0)
			(size 0 0)
			(layers "B.Cu" "B.Mask" "B.Paste")
			(net "PVDDCR_CPU0_P0")
		)
		(pad "2" smd circle
			(at -0.40005 0)
			(size 0 0)
			(layers "B.Cu" "B.Mask" "B.Paste")
			(net "GND")
		)
	)
	(footprint ""
		(layer "B.Cu")
		(at 351.506028 -395.148562 90)
		(property "Reference" "C613"
			(at 0 0 90)
			(layer "B.SilkS")
			(hide yes)
			(effects
				(font
					(size 1.27 1.27)
				)
				(justify mirror)
			)
		)
		(property "Value" ""
			(at 0 0 90)
			(layer "B.Fab")
			(effects
				(font
					(size 1.27 1.27)
				)
				(justify mirror)
			)
		)
		(duplicate_pad_numbers_are_jumpers no)
		(fp_line
			(start 0.299974 -0.150114)
			(end -0.299974 -0.150114)
			(stroke
				(width 0.1)
				(type default)
			)
			(layer "B.Fab")
		)
		(fp_line
			(start -0.299974 -0.150114)
			(end -0.299974 0.150114)
			(stroke
				(width 0.1)
				(type default)
			)
			(layer "B.Fab")
		)
		(fp_line
			(start 0.299974 0.150114)
			(end 0.299974 -0.150114)
			(stroke
				(width 0.1)
				(type default)
			)
			(layer "B.Fab")
		)
		(fp_line
			(start -0.299974 0.150114)
			(end 0.299974 0.150114)
			(stroke
				(width 0.1)
				(type default)
			)
			(layer "B.Fab")
		)
		(pad "1" smd rect
			(at 0.2667 0 270)
			(size 0.3048 0.381)
			(layers "B.Cu" "B.Mask" "B.Paste")
			(net "P0V9_CPU0_RT1_2A")
		)
		(pad "2" smd rect
			(at -0.2667 0 270)
			(size 0.3048 0.381)
			(layers "B.Cu" "B.Mask" "B.Paste")
			(net "GND")
		)
	)
	(footprint ""
		(layer "B.Cu")
		(at 26.641298 -388.637272 90)
		(property "Reference" "PC6636_2"
			(at 0 0 90)
			(layer "B.SilkS")
			(hide yes)
			(effects
				(font
					(size 1.27 1.27)
				)
				(justify mirror)
			)
		)
		(property "Value" ""
			(at 0 0 90)
			(layer "B.Fab")
			(effects
				(font
					(size 1.27 1.27)
				)
				(justify mirror)
			)
		)
		(duplicate_pad_numbers_are_jumpers no)
		(fp_line
			(start 1.524 -0.762)
			(end -1.524 -0.762)
			(stroke
				(width 0.1524)
				(type default)
			)
			(layer "B.SilkS")
		)
		(fp_line
			(start -1.524 -0.762)
			(end -1.524 0.762)
			(stroke
				(width 0.1524)
				(type default)
			)
			(layer "B.SilkS")
		)
		(fp_line
			(start 1.524 0.762)
			(end 1.524 -0.762)
			(stroke
				(width 0.1524)
				(type default)
			)
			(layer "B.SilkS")
		)
		(fp_line
			(start -1.524 0.762)
			(end 1.524 0.762)
			(stroke
				(width 0.1524)
				(type default)
			)
			(layer "B.SilkS")
		)
		(fp_line
			(start 1.1049 -0.724916)
			(end 1.1049 0.724916)
			(stroke
				(width 0.1)
				(type default)
			)
			(layer "B.Fab")
		)
		(fp_line
			(start -1.1049 -0.724916)
			(end 1.1049 -0.724916)
			(stroke
				(width 0.1)
				(type default)
			)
			(layer "B.Fab")
		)
		(fp_line
			(start 1.1049 0.724916)
			(end -1.1049 0.724916)
			(stroke
				(width 0.1)
				(type default)
			)
			(layer "B.Fab")
		)
		(fp_line
			(start -1.1049 0.724916)
			(end -1.1049 -0.724916)
			(stroke
				(width 0.1)
				(type default)
			)
			(layer "B.Fab")
		)
		(pad "1" smd rect
			(at 0.889 0 90)
			(size 1.016 1.27)
			(layers "B.Cu" "B.Mask" "B.Paste")
			(net "SW_P12V_AUX_P0V9_RETIMER_CPU1_FLT")
		)
		(pad "2" smd rect
			(at -0.889 0 90)
			(size 1.016 1.27)
			(layers "B.Cu" "B.Mask" "B.Paste")
			(net "GND")
		)
	)
	(footprint ""
		(layer "B.Cu")
		(at 289.697414 -347.77553 -90)
		(property "Reference" "PR99"
			(at 0 0 90)
			(layer "B.SilkS")
			(hide yes)
			(effects
				(font
					(size 1.27 1.27)
				)
				(justify mirror)
			)
		)
		(property "Value" ""
			(at 0 0 90)
			(layer "B.Fab")
			(effects
				(font
					(size 1.27 1.27)
				)
				(justify mirror)
			)
		)
		(duplicate_pad_numbers_are_jumpers no)
		(fp_line
			(start -0.7874 0.4064)
			(end 0.7874 0.4064)
			(stroke
				(width 0.1524)
				(type default)
			)
			(layer "B.SilkS")
		)
		(fp_line
			(start 0.7874 0.4064)
			(end 0.7874 -0.4064)
			(stroke
				(width 0.1524)
				(type default)
			)
			(layer "B.SilkS")
		)
		(fp_line
			(start -0.7874 -0.4064)
			(end -0.7874 0.4064)
			(stroke
				(width 0.1524)
				(type default)
			)
			(layer "B.SilkS")
		)
		(fp_line
			(start 0.7874 -0.4064)
			(end -0.7874 -0.4064)
			(stroke
				(width 0.1524)
				(type default)
			)
			(layer "B.SilkS")
		)
		(fp_line
			(start -0.67945 0.3048)
			(end -0.120396 0.3048)
			(stroke
				(width 0.1)
				(type default)
			)
			(layer "B.Fab")
		)
		(fp_line
			(start -0.120396 0.3048)
			(end -0.120396 0.2794)
			(stroke
				(width 0.1)
				(type default)
			)
			(layer "B.Fab")
		)
		(fp_line
			(start 0.12065 0.3048)
			(end 0.67945 0.3048)
			(stroke
				(width 0.1)
				(type default)
			)
			(layer "B.Fab")
		)
		(fp_line
			(start 0.67945 0.3048)
			(end 0.67945 -0.305054)
			(stroke
				(width 0.1)
				(type default)
			)
			(layer "B.Fab")
		)
		(fp_line
			(start -0.120396 0.2794)
			(end 0.12065 0.2794)
			(stroke
				(width 0.1)
				(type default)
			)
			(layer "B.Fab")
		)
		(fp_line
			(start 0.12065 0.2794)
			(end 0.12065 0.3048)
			(stroke
				(width 0.1)
				(type default)
			)
			(layer "B.Fab")
		)
		(fp_line
			(start -0.12065 -0.2794)
			(end -0.12065 -0.3048)
			(stroke
				(width 0.1)
				(type default)
			)
			(layer "B.Fab")
		)
		(fp_line
			(start 0.12065 -0.2794)
			(end -0.12065 -0.2794)
			(stroke
				(width 0.1)
				(type default)
			)
			(layer "B.Fab")
		)
		(fp_line
			(start -0.67945 -0.3048)
			(end -0.67945 0.3048)
			(stroke
				(width 0.1)
				(type default)
			)
			(layer "B.Fab")
		)
		(fp_line
			(start -0.12065 -0.3048)
			(end -0.67945 -0.3048)
			(stroke
				(width 0.1)
				(type default)
			)
			(layer "B.Fab")
		)
		(fp_line
			(start 0.12065 -0.305054)
			(end 0.12065 -0.2794)
			(stroke
				(width 0.1)
				(type default)
			)
			(layer "B.Fab")
		)
		(fp_line
			(start 0.67945 -0.305054)
			(end 0.12065 -0.305054)
			(stroke
				(width 0.1)
				(type default)
			)
			(layer "B.Fab")
		)
		(pad "1" smd circle
			(at 0.40005 0 90)
			(size 0 0)
			(layers "B.Cu" "B.Mask" "B.Paste")
			(net "PVDDCR_CPU1_P0_PVCC")
		)
		(pad "2" smd circle
			(at -0.40005 0 90)
			(size 0 0)
			(layers "B.Cu" "B.Mask" "B.Paste")
			(net "PVDDIO_P0_VCC2")
		)
	)
	(footprint ""
		(layer "B.Cu")
		(at 144.727676 -388.609078 90)
		(property "Reference" "C393"
			(at 0 0 90)
			(layer "B.SilkS")
			(hide yes)
			(effects
				(font
					(size 1.27 1.27)
				)
				(justify mirror)
			)
		)
		(property "Value" ""
			(at 0 0 90)
			(layer "B.Fab")
			(effects
				(font
					(size 1.27 1.27)
				)
				(justify mirror)
			)
		)
		(duplicate_pad_numbers_are_jumpers no)
		(fp_line
			(start 0.299974 -0.150114)
			(end -0.299974 -0.150114)
			(stroke
				(width 0.1)
				(type default)
			)
			(layer "B.Fab")
		)
		(fp_line
			(start -0.299974 -0.150114)
			(end -0.299974 0.150114)
			(stroke
				(width 0.1)
				(type default)
			)
			(layer "B.Fab")
		)
		(fp_line
			(start 0.299974 0.150114)
			(end 0.299974 -0.150114)
			(stroke
				(width 0.1)
				(type default)
			)
			(layer "B.Fab")
		)
		(fp_line
			(start -0.299974 0.150114)
			(end 0.299974 0.150114)
			(stroke
				(width 0.1)
				(type default)
			)
			(layer "B.Fab")
		)
		(pad "1" smd rect
			(at 0.2667 0 270)
			(size 0.3048 0.381)
			(layers "B.Cu" "B.Mask" "B.Paste")
			(net "P0V9_CPU1_RT2_2A")
		)
		(pad "2" smd rect
			(at -0.2667 0 270)
			(size 0.3048 0.381)
			(layers "B.Cu" "B.Mask" "B.Paste")
			(net "GND")
		)
	)
	(footprint ""
		(layer "B.Cu")
		(at 100.881434 -254.067564 180)
		(property "Reference" "C2292"
			(at 0 0 0)
			(layer "B.SilkS")
			(hide yes)
			(effects
				(font
					(size 1.27 1.27)
				)
				(justify mirror)
			)
		)
		(property "Value" ""
			(at 0 0 0)
			(layer "B.Fab")
			(effects
				(font
					(size 1.27 1.27)
				)
				(justify mirror)
			)
		)
		(duplicate_pad_numbers_are_jumpers no)
		(fp_line
			(start 0.7874 0.4064)
			(end 0.7874 -0.4064)
			(stroke
				(width 0.1524)
				(type default)
			)
			(layer "B.SilkS")
		)
		(fp_line
			(start 0.7874 -0.4064)
			(end -0.7874 -0.4064)
			(stroke
				(width 0.1524)
				(type default)
			)
			(layer "B.SilkS")
		)
		(fp_line
			(start -0.7874 0.4064)
			(end 0.7874 0.4064)
			(stroke
				(width 0.1524)
				(type default)
			)
			(layer "B.SilkS")
		)
		(fp_line
			(start -0.7874 -0.4064)
			(end -0.7874 0.4064)
			(stroke
				(width 0.1524)
				(type default)
			)
			(layer "B.SilkS")
		)
		(fp_line
			(start 0.67945 0.3048)
			(end 0.67945 -0.305054)
			(stroke
				(width 0.1)
				(type default)
			)
			(layer "B.Fab")
		)
		(fp_line
			(start 0.67945 -0.305054)
			(end 0.12065 -0.305054)
			(stroke
				(width 0.1)
				(type default)
			)
			(layer "B.Fab")
		)
		(fp_line
			(start 0.12065 0.3048)
			(end 0.67945 0.3048)
			(stroke
				(width 0.1)
				(type default)
			)
			(layer "B.Fab")
		)
		(fp_line
			(start 0.12065 0.2794)
			(end 0.12065 0.3048)
			(stroke
				(width 0.1)
				(type default)
			)
			(layer "B.Fab")
		)
		(fp_line
			(start 0.12065 -0.2794)
			(end -0.12065 -0.2794)
			(stroke
				(width 0.1)
				(type default)
			)
			(layer "B.Fab")
		)
		(fp_line
			(start 0.12065 -0.305054)
			(end 0.12065 -0.2794)
			(stroke
				(width 0.1)
				(type default)
			)
			(layer "B.Fab")
		)
		(fp_line
			(start -0.120396 0.3048)
			(end -0.120396 0.2794)
			(stroke
				(width 0.1)
				(type default)
			)
			(layer "B.Fab")
		)
		(fp_line
			(start -0.120396 0.2794)
			(end 0.12065 0.2794)
			(stroke
				(width 0.1)
				(type default)
			)
			(layer "B.Fab")
		)
		(fp_line
			(start -0.12065 -0.2794)
			(end -0.12065 -0.3048)
			(stroke
				(width 0.1)
				(type default)
			)
			(layer "B.Fab")
		)
		(fp_line
			(start -0.12065 -0.3048)
			(end -0.67945 -0.3048)
			(stroke
				(width 0.1)
				(type default)
			)
			(layer "B.Fab")
		)
		(fp_line
			(start -0.67945 0.3048)
			(end -0.120396 0.3048)
			(stroke
				(width 0.1)
				(type default)
			)
			(layer "B.Fab")
		)
		(fp_line
			(start -0.67945 -0.3048)
			(end -0.67945 0.3048)
			(stroke
				(width 0.1)
				(type default)
			)
			(layer "B.Fab")
		)
		(pad "1" smd circle
			(at 0.40005 0)
			(size 0 0)
			(layers "B.Cu" "B.Mask" "B.Paste")
			(net "PVDD18_S5_P1")
		)
		(pad "2" smd circle
			(at -0.40005 0)
			(size 0 0)
			(layers "B.Cu" "B.Mask" "B.Paste")
			(net "GND")
		)
	)
	(footprint ""
		(layer "B.Cu")
		(at 305.791108 -398.942052 90)
		(property "Reference" "C557"
			(at 0 0 90)
			(layer "B.SilkS")
			(hide yes)
			(effects
				(font
					(size 1.27 1.27)
				)
				(justify mirror)
			)
		)
		(property "Value" ""
			(at 0 0 90)
			(layer "B.Fab")
			(effects
				(font
					(size 1.27 1.27)
				)
				(justify mirror)
			)
		)
		(duplicate_pad_numbers_are_jumpers no)
		(fp_line
			(start 0.7874 -0.4064)
			(end -0.7874 -0.4064)
			(stroke
				(width 0.1524)
				(type default)
			)
			(layer "B.SilkS")
		)
		(fp_line
			(start -0.7874 -0.4064)
			(end -0.7874 0.4064)
			(stroke
				(width 0.1524)
				(type default)
			)
			(layer "B.SilkS")
		)
		(fp_line
			(start 0.7874 0.4064)
			(end 0.7874 -0.4064)
			(stroke
				(width 0.1524)
				(type default)
			)
			(layer "B.SilkS")
		)
		(fp_line
			(start -0.7874 0.4064)
			(end 0.7874 0.4064)
			(stroke
				(width 0.1524)
				(type default)
			)
			(layer "B.SilkS")
		)
		(fp_line
			(start 0.67945 -0.305054)
			(end 0.12065 -0.305054)
			(stroke
				(width 0.1)
				(type default)
			)
			(layer "B.Fab")
		)
		(fp_line
			(start 0.12065 -0.305054)
			(end 0.12065 -0.2794)
			(stroke
				(width 0.1)
				(type default)
			)
			(layer "B.Fab")
		)
		(fp_line
			(start -0.12065 -0.3048)
			(end -0.67945 -0.3048)
			(stroke
				(width 0.1)
				(type default)
			)
			(layer "B.Fab")
		)
		(fp_line
			(start -0.67945 -0.3048)
			(end -0.67945 0.3048)
			(stroke
				(width 0.1)
				(type default)
			)
			(layer "B.Fab")
		)
		(fp_line
			(start 0.12065 -0.2794)
			(end -0.12065 -0.2794)
			(stroke
				(width 0.1)
				(type default)
			)
			(layer "B.Fab")
		)
		(fp_line
			(start -0.12065 -0.2794)
			(end -0.12065 -0.3048)
			(stroke
				(width 0.1)
				(type default)
			)
			(layer "B.Fab")
		)
		(fp_line
			(start 0.12065 0.2794)
			(end 0.12065 0.3048)
			(stroke
				(width 0.1)
				(type default)
			)
			(layer "B.Fab")
		)
		(fp_line
			(start -0.120396 0.2794)
			(end 0.12065 0.2794)
			(stroke
				(width 0.1)
				(type default)
			)
			(layer "B.Fab")
		)
		(fp_line
			(start 0.67945 0.3048)
			(end 0.67945 -0.305054)
			(stroke
				(width 0.1)
				(type default)
			)
			(layer "B.Fab")
		)
		(fp_line
			(start 0.12065 0.3048)
			(end 0.67945 0.3048)
			(stroke
				(width 0.1)
				(type default)
			)
			(layer "B.Fab")
		)
		(fp_line
			(start -0.120396 0.3048)
			(end -0.120396 0.2794)
			(stroke
				(width 0.1)
				(type default)
			)
			(layer "B.Fab")
		)
		(fp_line
			(start -0.67945 0.3048)
			(end -0.120396 0.3048)
			(stroke
				(width 0.1)
				(type default)
			)
			(layer "B.Fab")
		)
		(pad "1" smd circle
			(at 0.40005 0 270)
			(size 0 0)
			(layers "B.Cu" "B.Mask" "B.Paste")
			(net "P0V9_CPU0_RT0_2A")
		)
		(pad "2" smd circle
			(at -0.40005 0 270)
			(size 0 0)
			(layers "B.Cu" "B.Mask" "B.Paste")
			(net "GND")
		)
	)
)
